(kicad_pcb
	(version 20260206)
	(generator "pcbnew")
	(generator_version "10.0")
	(general
		(thickness 1.6)
		(legacy_teardrops no)
	)
	(paper "A4")
	(title_block
		(title "baseboard — 13948-1b.1110WZS1818.brd")
		(comment 1 "Honey Badger (Wiwynn) / footprints 125-131 of 2523")
	)
	(layers
		(0 "F.Cu" signal "TOP")
		(4 "In1.Cu" signal "L2GND")
		(6 "In2.Cu" signal "L3")
		(8 "In3.Cu" signal "L4VCC")
		(10 "In4.Cu" signal "L5VCC")
		(12 "In5.Cu" signal "L6")
		(14 "In6.Cu" signal "L7GND")
		(2 "B.Cu" signal "BOTTOM")
		(9 "F.Adhes" user "F.Adhesive")
		(11 "B.Adhes" user "B.Adhesive")
		(13 "F.Paste" user "Package Geometry/Pastemask Top")
		(15 "B.Paste" user "Package Geometry/Pastemask Bottom")
		(5 "F.SilkS" user "Ref Des/Silkscreen Top")
		(7 "B.SilkS" user "Ref Des/Silkscreen Bottom")
		(1 "F.Mask" user "Board Geometry/Soldermask Top")
		(3 "B.Mask" user "Board Geometry/Soldermask Bottom")
		(17 "Dwgs.User" user "User.Drawings")
		(19 "Cmts.User" user "User.Comments")
		(21 "Eco1.User" user "User.Eco1")
		(23 "Eco2.User" user "User.Eco2")
		(25 "Edge.Cuts" user "Board Geometry/Outline")
		(27 "Margin" user)
		(31 "F.CrtYd" user "Package Geometry/Place Bound Top")
		(29 "B.CrtYd" user "Package Geometry/Place Bound Bottom")
		(35 "F.Fab" user "Ref Des/Assembly Top")
		(33 "B.Fab" user "Ref Des/Assembly Bottom")
	)
	(footprint ""
		(layer "F.Cu")
		(at 8.713216 -226.62388 180)
		(property "Reference" "R155"
			(at 0 0 180)
			(layer "F.SilkS")
			(hide yes)
			(effects
				(font
					(size 1.27 1.27)
				)
			)
		)
		(property "Value" "0R2J-2-GP"
			(at 0.064008 -3.993896 180)
			(unlocked yes)
			(layer "F.Fab")
			(hide yes)
			(effects
				(font
					(size 1.016 1.016)
					(thickness 0.1524)
				)
			)
		)
		(property "Device Type" "R402H16"
			(at 0.064008 -5.517896 180)
			(unlocked yes)
			(layer "F.Fab")
			(hide yes)
			(effects
				(font
					(size 1.016 1.016)
					(thickness 0.1524)
				)
			)
		)
		(duplicate_pad_numbers_are_jumpers no)
		(fp_line
			(start 0.508 -0.9398)
			(end -0.508 -0.9398)
			(stroke
				(width 0.1524)
				(type default)
			)
			(layer "F.SilkS")
		)
		(fp_line
			(start -0.508 -0.9398)
			(end -0.508 0.9398)
			(stroke
				(width 0.1524)
				(type default)
			)
			(layer "F.SilkS")
		)
		(fp_rect
			(start -0.508 0.9398)
			(end 0.508 -0.9398)
			(stroke
				(width 0)
				(type default)
			)
			(fill no)
			(layer "F.CrtYd")
		)
		(fp_rect
			(start -0.508 0.9398)
			(end 0.508 -0.9398)
			(stroke
				(width 0)
				(type default)
			)
			(fill no)
			(layer "F.Fab")
		)
		(pad "1" smd custom
			(at 0 -0.4445 180)
			(size 0.1397 0.1397)
			(layers "F.Cu" "F.Mask" "F.Paste")
			(net "BMC_SELF_TRAY")
			(options
				(clearance outline)
				(anchor circle)
			)
			(primitives
				(gr_poly
					(pts
						(arc
							(start -0.1778 -0.2794)
							(mid -0.249642 -0.249642)
							(end -0.2794 -0.1778)
						)
						(arc
							(start -0.2794 0.1778)
							(mid -0.249642 0.249642)
							(end -0.1778 0.2794)
						)
						(arc
							(start 0.1778 0.2794)
							(mid 0.249642 0.249642)
							(end 0.2794 0.1778)
						)
						(arc
							(start 0.2794 -0.1778)
							(mid 0.249642 -0.249642)
							(end 0.1778 -0.2794)
						)
					)
					(width 0)
					(fill yes)
				)
			)
		)
		(pad "2" smd custom
			(at 0 0.4445 180)
			(size 0.1397 0.1397)
			(layers "F.Cu" "F.Mask" "F.Paste")
			(net "SELF_TRAY")
			(options
				(clearance outline)
				(anchor circle)
			)
			(primitives
				(gr_poly
					(pts
						(arc
							(start -0.1778 -0.2794)
							(mid -0.249642 -0.249642)
							(end -0.2794 -0.1778)
						)
						(arc
							(start -0.2794 0.1778)
							(mid -0.249642 0.249642)
							(end -0.1778 0.2794)
						)
						(arc
							(start 0.1778 0.2794)
							(mid 0.249642 0.249642)
							(end 0.2794 0.1778)
						)
						(arc
							(start 0.2794 -0.1778)
							(mid 0.249642 -0.249642)
							(end 0.1778 -0.2794)
						)
					)
					(width 0)
					(fill yes)
				)
			)
		)
	)
	(footprint ""
		(layer "F.Cu")
		(at 188.595 -15.24 -90)
		(property "Reference" "U15"
			(at 0 0 270)
			(layer "F.SilkS")
			(hide yes)
			(effects
				(font
					(size 1.27 1.27)
				)
			)
		)
		(property "Value" "TMP421AIDCNRG4-GP"
			(at -5.08 -8.5852 270)
			(unlocked yes)
			(layer "F.Fab")
			(hide yes)
			(effects
				(font
					(size 1.016 1.016)
					(thickness 0.1524)
				)
			)
		)
		(property "Device Type" "SOT23-8PH58"
			(at -5.08 -10.1092 270)
			(unlocked yes)
			(layer "F.Fab")
			(hide yes)
			(effects
				(font
					(size 1.016 1.016)
					(thickness 0.1524)
				)
			)
		)
		(duplicate_pad_numbers_are_jumpers no)
		(fp_line
			(start -1.8796 0.5588)
			(end -1.8796 -0.5588)
			(stroke
				(width 0.1524)
				(type default)
			)
			(layer "F.SilkS")
		)
		(fp_line
			(start -1.7018 0.5588)
			(end -1.7018 2.1082)
			(stroke
				(width 0.508)
				(type default)
			)
			(layer "F.SilkS")
		)
		(fp_line
			(start 1.8796 0.5588)
			(end -1.8796 0.5588)
			(stroke
				(width 0.1524)
				(type default)
			)
			(layer "F.SilkS")
		)
		(fp_line
			(start -1.6256 0)
			(end -1.8796 0.254)
			(stroke
				(width 0.1524)
				(type default)
			)
			(layer "F.SilkS")
		)
		(fp_line
			(start -1.8796 -0.254)
			(end -1.6256 0)
			(stroke
				(width 0.1524)
				(type default)
			)
			(layer "F.SilkS")
		)
		(fp_line
			(start -1.8796 -0.5588)
			(end 1.8796 -0.5588)
			(stroke
				(width 0.1524)
				(type default)
			)
			(layer "F.SilkS")
		)
		(fp_line
			(start 1.8796 -0.5588)
			(end 1.8796 0.5588)
			(stroke
				(width 0.1524)
				(type default)
			)
			(layer "F.SilkS")
		)
		(fp_poly
			(pts
				(xy -1.15316 0.5588) (xy 1.8796 0.5588) (xy 1.8796 -0.5588) (xy -1.15316 -0.5588)
			)
			(stroke
				(width 0)
				(type default)
			)
			(fill yes)
			(layer "F.SilkS")
		)
		(fp_rect
			(start -1.9558 2.3622)
			(end 1.9558 -2.3622)
			(stroke
				(width 0)
				(type default)
			)
			(fill no)
			(layer "F.CrtYd")
		)
		(fp_poly
			(pts
				(xy -1.9558 -2.3622) (xy 1.9558 -2.3622) (xy 1.9558 2.3622) (xy -1.9558 2.3622)
			)
			(stroke
				(width 0)
				(type default)
			)
			(fill no)
			(layer "F.Fab")
		)
		(pad "1" smd rect
			(at -0.97536 1.3462 270)
			(size 0.3556 1.016)
			(layers "F.Cu" "F.Mask" "F.Paste")
			(net "TEMP_SENSOR_DXP")
		)
		(pad "2" smd rect
			(at -0.32512 1.3462 270)
			(size 0.3556 1.016)
			(layers "F.Cu" "F.Mask" "F.Paste")
			(net "TEMP_SENSOR_DXN")
		)
		(pad "3" smd rect
			(at 0.32512 1.3462 270)
			(size 0.3556 1.016)
			(layers "F.Cu" "F.Mask" "F.Paste")
			(net "TEMP_1_A1")
		)
		(pad "4" smd rect
			(at 0.97409 1.3462 270)
			(size 0.3556 1.016)
			(layers "F.Cu" "F.Mask" "F.Paste")
			(net "TEMP_1_A0")
		)
		(pad "5" smd rect
			(at 0.97409 -1.3462 270)
			(size 0.3556 1.016)
			(layers "F.Cu" "F.Mask" "F.Paste")
			(net "GND")
		)
		(pad "6" smd rect
			(at 0.32512 -1.3462 270)
			(size 0.3556 1.016)
			(layers "F.Cu" "F.Mask" "F.Paste")
			(net "TEMP_1_SDA")
		)
		(pad "7" smd rect
			(at -0.32512 -1.3462 270)
			(size 0.3556 1.016)
			(layers "F.Cu" "F.Mask" "F.Paste")
			(net "TEMP_1_SCL")
		)
		(pad "8" smd rect
			(at -0.97536 -1.3462 270)
			(size 0.3556 1.016)
			(layers "F.Cu" "F.Mask" "F.Paste")
			(net "P3V3_STBY")
		)
	)
	(footprint ""
		(layer "F.Cu")
		(at 86.49716 -33.655 -90)
		(property "Reference" "SC878"
			(at 0 0 270)
			(layer "F.SilkS")
			(hide yes)
			(effects
				(font
					(size 1.27 1.27)
				)
			)
		)
		(property "Value" "SCD01U10V1KX-GP"
			(at -2.8321 -1.7399 270)
			(unlocked yes)
			(layer "F.Fab")
			(hide yes)
			(effects
				(font
					(size 1.016 1.016)
					(thickness 0.1524)
				)
			)
		)
		(property "Device Type" "C0201H13"
			(at -2.8321 -3.2639 270)
			(unlocked yes)
			(layer "F.Fab")
			(hide yes)
			(effects
				(font
					(size 1.016 1.016)
					(thickness 0.1524)
				)
			)
		)
		(duplicate_pad_numbers_are_jumpers no)
		(fp_rect
			(start -0.2794 0.6477)
			(end 0.2794 -0.6477)
			(stroke
				(width 0)
				(type default)
			)
			(fill no)
			(layer "F.CrtYd")
		)
		(fp_rect
			(start -0.2794 0.6477)
			(end 0.2794 -0.6477)
			(stroke
				(width 0)
				(type default)
			)
			(fill no)
			(layer "F.Fab")
		)
		(pad "1" smd custom
			(at 0 -0.2794 270)
			(size 0.0762 0.0762)
			(layers "F.Cu" "F.Mask" "F.Paste")
			(net "SAS3008_RAID_TX_C_P0")
			(options
				(clearance outline)
				(anchor circle)
			)
			(primitives
				(gr_poly
					(pts
						(arc
							(start 0.1524 -0.127)
							(mid 0.137521 -0.162921)
							(end 0.1016 -0.1778)
						)
						(arc
							(start -0.1016 -0.1778)
							(mid -0.137521 -0.162921)
							(end -0.1524 -0.127)
						)
						(arc
							(start -0.1524 0.127)
							(mid -0.137521 0.162921)
							(end -0.1016 0.1778)
						)
						(arc
							(start 0.1016 0.1778)
							(mid 0.137521 0.162921)
							(end 0.1524 0.127)
						)
					)
					(width 0)
					(fill yes)
				)
			)
		)
		(pad "2" smd custom
			(at 0 0.2794 270)
			(size 0.0762 0.0762)
			(layers "F.Cu" "F.Mask" "F.Paste")
			(net "SAS3008_RAID_TX_P0")
			(options
				(clearance outline)
				(anchor circle)
			)
			(primitives
				(gr_poly
					(pts
						(arc
							(start 0.1524 -0.127)
							(mid 0.137521 -0.162921)
							(end 0.1016 -0.1778)
						)
						(arc
							(start -0.1016 -0.1778)
							(mid -0.137521 -0.162921)
							(end -0.1524 -0.127)
						)
						(arc
							(start -0.1524 0.127)
							(mid -0.137521 0.162921)
							(end -0.1016 0.1778)
						)
						(arc
							(start 0.1016 0.1778)
							(mid 0.137521 0.162921)
							(end 0.1524 0.127)
						)
					)
					(width 0)
					(fill yes)
				)
			)
		)
	)
	(footprint ""
		(layer "F.Cu")
		(at 276.479 -192.405)
		(property "Reference" "L6"
			(at 0 0 0)
			(layer "F.SilkS")
			(hide yes)
			(effects
				(font
					(size 1.27 1.27)
				)
			)
		)
		(property "Value" "MMZ2012S601ATA1N-GP"
			(at 0 -4.2418 0)
			(unlocked yes)
			(layer "F.Fab")
			(hide yes)
			(effects
				(font
					(size 1.016 1.016)
					(thickness 0.1524)
				)
			)
		)
		(property "Device Type" "L805H42"
			(at 0 -5.7912 0)
			(unlocked yes)
			(layer "F.Fab")
			(hide yes)
			(effects
				(font
					(size 1.016 1.016)
					(thickness 0.1524)
				)
			)
		)
		(duplicate_pad_numbers_are_jumpers no)
		(fp_line
			(start -0.889 -1.7018)
			(end 0.889 -1.7018)
			(stroke
				(width 0.1524)
				(type default)
			)
			(layer "F.SilkS")
		)
		(fp_line
			(start -0.889 1.7018)
			(end -0.889 -1.7018)
			(stroke
				(width 0.1524)
				(type default)
			)
			(layer "F.SilkS")
		)
		(fp_line
			(start 0.889 -1.7018)
			(end 0.889 1.7018)
			(stroke
				(width 0.1524)
				(type default)
			)
			(layer "F.SilkS")
		)
		(fp_line
			(start 0.889 1.7018)
			(end -0.889 1.7018)
			(stroke
				(width 0.1524)
				(type default)
			)
			(layer "F.SilkS")
		)
		(fp_rect
			(start -0.9652 1.778)
			(end 0.9652 -1.778)
			(stroke
				(width 0)
				(type default)
			)
			(fill no)
			(layer "F.CrtYd")
		)
		(fp_rect
			(start -0.9652 1.778)
			(end 0.9652 -1.778)
			(stroke
				(width 0)
				(type default)
			)
			(fill no)
			(layer "F.Fab")
		)
		(pad "1" smd rect
			(at 0 -0.9652)
			(size 1.397 1.143)
			(layers "F.Cu" "F.Mask" "F.Paste")
			(net "P1V26_STBY")
		)
		(pad "2" smd rect
			(at 0 0.9652)
			(size 1.397 1.143)
			(layers "F.Cu" "F.Mask" "F.Paste")
			(net "V1PLLAV12")
		)
	)
	(footprint ""
		(layer "F.Cu")
		(at 268.478 -16.383 180)
		(property "Reference" "TC11"
			(at 0 0 180)
			(layer "F.SilkS")
			(hide yes)
			(effects
				(font
					(size 1.27 1.27)
				)
			)
		)
		(property "Value" "SC47U16V0MX-GP"
			(at -0.00254 -4.78536 180)
			(unlocked yes)
			(layer "F.Fab")
			(hide yes)
			(effects
				(font
					(size 1.016 1.016)
					(thickness 0.1524)
				)
			)
		)
		(property "Device Type" "C1210H107"
			(at -0.00254 -6.38048 180)
			(unlocked yes)
			(layer "F.Fab")
			(hide yes)
			(effects
				(font
					(size 1.016 1.016)
					(thickness 0.1524)
				)
			)
		)
		(duplicate_pad_numbers_are_jumpers no)
		(fp_line
			(start 1.5748 2.3368)
			(end 1.5748 0.762)
			(stroke
				(width 0.1524)
				(type default)
			)
			(layer "F.SilkS")
		)
		(fp_line
			(start 1.5748 -0.762)
			(end 1.5748 -2.3368)
			(stroke
				(width 0.1524)
				(type default)
			)
			(layer "F.SilkS")
		)
		(fp_line
			(start 1.5748 -2.3368)
			(end -1.5748 -2.3368)
			(stroke
				(width 0.1524)
				(type default)
			)
			(layer "F.SilkS")
		)
		(fp_line
			(start -1.5748 2.3368)
			(end 1.5748 2.3368)
			(stroke
				(width 0.1524)
				(type default)
			)
			(layer "F.SilkS")
		)
		(fp_line
			(start -1.5748 0.762)
			(end -1.5748 2.3368)
			(stroke
				(width 0.1524)
				(type default)
			)
			(layer "F.SilkS")
		)
		(fp_line
			(start -1.5748 -2.3368)
			(end -1.5748 -0.762)
			(stroke
				(width 0.1524)
				(type default)
			)
			(layer "F.SilkS")
		)
		(fp_rect
			(start -1.651 2.413)
			(end 1.651 -2.413)
			(stroke
				(width 0)
				(type default)
			)
			(fill no)
			(layer "F.CrtYd")
		)
		(fp_poly
			(pts
				(xy 1.651 2.413) (xy 1.651 -2.413) (xy -1.651 -2.413) (xy -1.651 2.413)
			)
			(stroke
				(width 0)
				(type default)
			)
			(fill no)
			(layer "F.Fab")
		)
		(pad "1" smd rect
			(at 0 -1.4732 180)
			(size 2.794 1.397)
			(layers "F.Cu" "F.Mask" "F.Paste")
			(net "P5V_USB")
		)
		(pad "2" smd rect
			(at 0 1.4732 180)
			(size 2.794 1.397)
			(layers "F.Cu" "F.Mask" "F.Paste")
			(net "GND")
		)
	)
	(footprint ""
		(layer "F.Cu")
		(at 194.563492 -180.226716)
		(property "Reference" "R483"
			(at 0 0 0)
			(layer "F.SilkS")
			(hide yes)
			(effects
				(font
					(size 1.27 1.27)
				)
			)
		)
		(property "Value" "0R2J-2-GP"
			(at 0.064008 -3.993896 0)
			(unlocked yes)
			(layer "F.Fab")
			(hide yes)
			(effects
				(font
					(size 1.016 1.016)
					(thickness 0.1524)
				)
			)
		)
		(property "Device Type" "R402H16"
			(at 0.064008 -5.517896 0)
			(unlocked yes)
			(layer "F.Fab")
			(hide yes)
			(effects
				(font
					(size 1.016 1.016)
					(thickness 0.1524)
				)
			)
		)
		(duplicate_pad_numbers_are_jumpers no)
		(fp_line
			(start -0.508 -0.9398)
			(end -0.508 0.9398)
			(stroke
				(width 0.1524)
				(type default)
			)
			(layer "F.SilkS")
		)
		(fp_line
			(start 0.508 -0.9398)
			(end -0.508 -0.9398)
			(stroke
				(width 0.1524)
				(type default)
			)
			(layer "F.SilkS")
		)
		(fp_rect
			(start -0.508 0.9398)
			(end 0.508 -0.9398)
			(stroke
				(width 0)
				(type default)
			)
			(fill no)
			(layer "F.CrtYd")
		)
		(fp_rect
			(start -0.508 0.9398)
			(end 0.508 -0.9398)
			(stroke
				(width 0)
				(type default)
			)
			(fill no)
			(layer "F.Fab")
		)
		(pad "1" smd custom
			(at 0 -0.4445)
			(size 0.1397 0.1397)
			(layers "F.Cu" "F.Mask" "F.Paste")
			(net "HB_A_OUT")
			(options
				(clearance outline)
				(anchor circle)
			)
			(primitives
				(gr_poly
					(pts
						(arc
							(start -0.1778 -0.2794)
							(mid -0.249642 -0.249642)
							(end -0.2794 -0.1778)
						)
						(arc
							(start -0.2794 0.1778)
							(mid -0.249642 0.249642)
							(end -0.1778 0.2794)
						)
						(arc
							(start 0.1778 0.2794)
							(mid 0.249642 0.249642)
							(end 0.2794 0.1778)
						)
						(arc
							(start 0.2794 -0.1778)
							(mid 0.249642 -0.249642)
							(end 0.1778 -0.2794)
						)
					)
					(width 0)
					(fill yes)
				)
			)
		)
		(pad "2" smd custom
			(at 0 0.4445)
			(size 0.1397 0.1397)
			(layers "F.Cu" "F.Mask" "F.Paste")
			(net "HB_OUT")
			(options
				(clearance outline)
				(anchor circle)
			)
			(primitives
				(gr_poly
					(pts
						(arc
							(start -0.1778 -0.2794)
							(mid -0.249642 -0.249642)
							(end -0.2794 -0.1778)
						)
						(arc
							(start -0.2794 0.1778)
							(mid -0.249642 0.249642)
							(end -0.1778 0.2794)
						)
						(arc
							(start 0.1778 0.2794)
							(mid 0.249642 0.249642)
							(end 0.2794 0.1778)
						)
						(arc
							(start 0.2794 -0.1778)
							(mid 0.249642 -0.249642)
							(end 0.1778 -0.2794)
						)
					)
					(width 0)
					(fill yes)
				)
			)
		)
	)
	(footprint ""
		(layer "F.Cu")
		(at 332.105 -94.234 90)
		(property "Reference" "PC37"
			(at 0 0 90)
			(layer "F.SilkS")
			(hide yes)
			(effects
				(font
					(size 1.27 1.27)
				)
			)
		)
		(property "Value" "SC100U6D3V6MX-GP"
			(at -0.0762 -5.1308 90)
			(unlocked yes)
			(layer "F.Fab")
			(hide yes)
			(effects
				(font
					(size 1.016 1.016)
					(thickness 0.1524)
				)
			)
		)
		(property "Device Type" "C1206H71"
			(at -0.127 -6.6548 90)
			(unlocked yes)
			(layer "F.Fab")
			(hide yes)
			(effects
				(font
					(size 1.016 1.016)
					(thickness 0.1524)
				)
			)
		)
		(duplicate_pad_numbers_are_jumpers no)
		(fp_line
			(start 1.016 -2.2352)
			(end 1.016 -0.8382)
			(stroke
				(width 0.1524)
				(type default)
			)
			(layer "F.SilkS")
		)
		(fp_line
			(start -1.016 -2.2352)
			(end 1.016 -2.2352)
			(stroke
				(width 0.1524)
				(type default)
			)
			(layer "F.SilkS")
		)
		(fp_line
			(start -1.016 -0.8382)
			(end -1.016 -2.2352)
			(stroke
				(width 0.1524)
				(type default)
			)
			(layer "F.SilkS")
		)
		(fp_line
			(start 1.016 0.8382)
			(end 1.016 2.2352)
			(stroke
				(width 0.1524)
				(type default)
			)
			(layer "F.SilkS")
		)
		(fp_line
			(start 1.016 2.2352)
			(end -1.016 2.2352)
			(stroke
				(width 0.1524)
				(type default)
			)
			(layer "F.SilkS")
		)
		(fp_line
			(start -1.016 2.2352)
			(end -1.016 0.8382)
			(stroke
				(width 0.1524)
				(type default)
			)
			(layer "F.SilkS")
		)
		(fp_rect
			(start -1.0922 2.3114)
			(end 1.0922 -2.3114)
			(stroke
				(width 0)
				(type default)
			)
			(fill no)
			(layer "F.CrtYd")
		)
		(fp_poly
			(pts
				(xy 1.0922 -2.3114) (xy 1.0922 2.3114) (xy -1.0922 2.3114) (xy -1.0922 -2.3114)
			)
			(stroke
				(width 0)
				(type default)
			)
			(fill no)
			(layer "F.Fab")
		)
		(pad "1" smd rect
			(at 0 -1.397 90)
			(size 1.651 1.27)
			(layers "F.Cu" "F.Mask" "F.Paste")
			(net "P3V3_STBY")
		)
		(pad "2" smd rect
			(at 0 1.397 90)
			(size 1.651 1.27)
			(layers "F.Cu" "F.Mask" "F.Paste")
			(net "GND")
		)
	)
)
